FILE_TYPE = CONNECTIVITY;
{Allegro Design Entry HDL 16.6-p007 (v16-6-112F) 10/10/2012}
"PAGE_NUMBER" = 239;
0"NC";
1"GND\g";
2"GND\g";
3"P3V3_STBY\g";
4"GND\g";
5"GND\g";
6"GND\g";
7"GND\g";
8"P3V3_STBY\g";
9"GND\g";
10"GND\g";
11"P3V3_STBY\g";
12"P3V3_STBY\g";
13"GND\g";
14"GND\g";
15"GND\g";
16"GND\g";
17"GND\g";
18"GND\g";
19"GND\g";
20"P2V5_AUX_BMC\g";
21"P1V2_AUX_BMC\g"VOLTAGE"1.5";
22"VR_P1V2_BMC_STBY_FB";
23"PWRGD_P3V3_STBY";
24"PWRGD_P2V5_BMC_STBY";
25"PWRGD_P1V2_BMC_STBY_R";
26"PWRGD_P2V5_BMC_STBY";
27"PWRGD_P2V5_BMC_STBY_R";
28"VR_P2V5_BMC_STBY_FB";
29"PWRGD_P1V2_BMC_STBY";
%"RES"
"2","(10350,3075)","0","mstr_discrete","I100";
;
CDS_SEC"1"
TOLERANCE"1%"
VALUE"10.0K"
LOCATION"R9F32"
PACK_TYPE"0402"
WATTAGE"1/16W"
PART_NUMBER"G21796-016"
MATERIAL"CHIP"
ROOM"CPU0"
BOM_COST"PROC_SIDEBAND"
CDS_LIB"mstr_discrete"
SEC_TYPE"0402"
SEC"1"
CDS_LOCATION"R9F32";
"A"
$PN"1"22;
"B"
$PN"2"2;
%"RES"
"2","(9925,800)","0","mstr_discrete","I101";
;
CDS_SEC"1"
PACK_TYPE"0402"
LOCATION"R9W32"
VALUE"10.0K"
PART_NUMBER"G21796-016"
TOLERANCE"1%"
WATTAGE"1/16W"
MATERIAL"CHIP"
SEC"1"
SEC_TYPE"0402"
CDS_LIB"mstr_discrete"
BOM_COST"PROC_SIDEBAND"
ROOM"CPU0"
CDS_LOCATION"R9W32";
"A"
$PN"1"28;
"B"
$PN"2"15;
%"21K5R2F-GP"
"1","(9925,1325)","0","w_hdl","I102";
;
CDS_SEC"1"
CDS_LOCATION"R9W31"
VALUE"21K5R2F-GP"
LOCATION"R9W31"
TOLERANCE"1%"
ATTRIBUTE"21.5KOHM"
PACK_SIZE"0402"
RATED"1/16W"
PACK_TYPE"RCL_GP"
SEC"1"
SEC_TYPE"RCL_GP"
PART_NUMBER"64.21525.6DL"
CDS_LIB"w_hdl"
CDS_LMAN_SYM_OUTLINE"-50,75,50,-75";
"2"
$PN"2"28;
"1"
$PN"1"20;
%"CAP"
"1","(6550,4250)","0","mstr_discrete","I104";
;
PART_NUMBER"E15431-002"
TOLERANCE"20%"
MATERIAL"X6S"
PACK_TYPE"0603"
LOCATION"C9W17"
VOLTAGE"6.3V"
POP"NOPOP"
VALUE"10UF"
CDS_LOCATION"C9W17"
CDS_SEC"1"
SEC"1"
SEC_TYPE"0603"
ROOM"P1V26_BMC_STBY_VR"
BOM_COST"P1V26_BMC_STBY_VR"
CDS_LIB"mstr_discrete";
"A"
$PN"1"8;
"B"
$PN"2"1;
%"GND"
"1","(6550,4025)","0","mstr_symbols","I105";
;
CDS_LIB"mstr_symbols"
SIZE"1B"
VOLTAGE"0.0V"
BODY_TYPE"PLUMBING"
HDL_POWER"GND";
"A\NAC"1;
%"CAP_A"
"1","(11250,3650)","0","dev_discrete","I111";
;
LOCATION"C9W19"
POP"NOPOP"
PART_NUMBER"E15431-004"
PACK_TYPE"0603V"
MATERIAL"X6S"
TOLERANCE"20%"
VOLTAGE"4V"
VALUE"22.0UF"
CDS_LOCATION"C9W19"
ROOM"PVCCIN_CPU0_DECAP_VR"
$SEC"1"
CDS_SEC"1"
CDS_LIB"dev_discrete"
BOM_COST"PROC_SOCKET";
"B"
$PN"2"17;
"A"
$PN"1"21;
%"CAP"
"1","(10875,3625)","0","mstr_discrete","I12";
;
CDS_SEC"1"
VOLTAGE"6.3V"
TOLERANCE"20%"
MATERIAL"X6S"
PACK_TYPE"0603"
PART_NUMBER"E15431-002"
LOCATION"C1T15"
VALUE"10UF"
BOM_COST"P1V538_BMC_STBY_VR"
ROOM"P1V538_BMC_STBY_VR"
SEC_TYPE"0603"
SEC"1"
CDS_LIB"mstr_discrete"
CDS_LOCATION"C1T15";
"A"
$PN"1"21;
"B"
$PN"2"17;
%"GND"
"1","(10350,2900)","0","mstr_symbols","I16";
;
P1V5_STBY_IBMC_VR""
P1V5_STBY_IBMC""
HDL_POWER"GND"
BODY_TYPE"PLUMBING"
ROOM"P1V538_BMC_STBY_VR"
VOLTAGE"0.0V"
SIZE"1B"
CDS_LIB"mstr_symbols"
BOM_COST"P1V538_BMC_STBY_VR";
"A\NAC"2;
%"CAP"
"1","(5750,4150)","0","mstr_discrete","I22";
;
CDS_SEC"1"
PART_NUMBER"E15431-002"
MATERIAL"X6S"
VOLTAGE"6.3V"
TOLERANCE"20%"
LOCATION"C1T7"
VALUE"10UF"
PACK_TYPE"0603"
CDS_LIB"mstr_discrete"
CDS_LOCATION"C1T7"
SEC"1"
SEC_TYPE"0603"
ROOM"P1V538_BMC_STBY_VR"
BOM_COST"P1V538_BMC_STBY_VR";
"A"
$PN"1"8;
"B"
$PN"2"5;
%"CAP"
"1","(7050,3300)","2","mstr_discrete","I30";
;
PACK_TYPE"0402LF"
PART_NUMBER"A36096-046"
VOLTAGE"50V"
TOLERANCE"10%"
LOCATION"C9F6"
VALUE"1000PF"
MATERIAL"EMPTY"
BOM_COST"P1V538_BMC_STBY_VR"
ROOM"P1V538_BMC_STBY_VR"
$SEC"1"
CDS_LOCATION"C9F6"
CDS_LIB"mstr_discrete"
CDS_SEC"1";
"A"
$PN"1"26;
"B"
$PN"2"4;
%"P3V3_STBY"
"1","(9625,5000)","0","mstr_symbols","I35";
;
HDL_POWER"P3V3_STBY"
BODY_TYPE"PLUMBING"
VOLTAGE"3.3V"
SIZE"1B"
CDS_LIB"mstr_symbols";
"G\NAC"3;
%"GND"
"1","(7050,2875)","0","mstr_symbols","I38";
;
P1V5_STBY_IBMC_VR""
P1V5_STBY_IBMC""
HDL_POWER"GND"
BODY_TYPE"PLUMBING"
ROOM"P1V538_BMC_STBY_VR"
SIZE"1B"
VOLTAGE"0.0V"
BOM_COST"P1V538_BMC_STBY_VR"
CDS_LIB"mstr_symbols";
"A\NAC"4;
%"GND"
"1","(5750,3850)","0","mstr_symbols","I39";
;
HDL_POWER"GND"
BODY_TYPE"PLUMBING"
VOLTAGE"0.0V"
SIZE"1B"
CDS_LIB"mstr_symbols";
"A\NAC"5;
%"CAP"
"1","(10375,4150)","0","mstr_discrete","I4";
;
PACK_TYPE"0402LF"
LOCATION"C9F10"
MATERIAL"X7R"
TOLERANCE"10%"
VALUE"1000PF"
VOLTAGE"50V"
PART_NUMBER"A36096-046"
ROOM"P1V538_BMC_STBY_VR"
BOM_COST"P1V538_BMC_STBY_VR"
$SEC"1"
CDS_LOCATION"C9F10"
CDS_LIB"mstr_discrete"
CDS_SEC"1";
"A"
$PN"1"25;
"B"
$PN"2"6;
%"GND"
"1","(10375,3975)","0","mstr_symbols","I5";
;
HDL_POWER"GND"
BODY_TYPE"PLUMBING"
ROOM"P1V538_BMC_STBY_VR"
VOLTAGE"0.0V"
SIZE"1B"
BOM_COST"P1V538_BMC_STBY_VR"
CDS_LIB"mstr_symbols";
"A\NAC"6;
%"RES"
"2","(9625,4525)","0","mstr_discrete","I6";
;
CDS_SEC"1"
MATERIAL"CHIP"
PART_NUMBER"G21796-016"
PACK_TYPE"0402"
P1V5_STBY_IBMC_VR""
P1V5_STBY_IBMC""
LOCATION"R9F12"
VALUE"10.0K"
TOLERANCE"1%"
WATTAGE"1/16W"
ROOM"P1V538_BMC_STBY_VR"
BOM_COST"P1V538_BMC_STBY_VR"
SEC"1"
SEC_TYPE"0402"
CDS_LIB"mstr_discrete"
CDS_LOCATION"R9F12";
"A"
$PN"1"3;
"B"
$PN"2"25;
%"GND"
"1","(9450,3350)","0","mstr_symbols","I62";
;
P1V5_STBY_IBMC""
P1V5_STBY_IBMC_VR""
HDL_POWER"GND"
BODY_TYPE"PLUMBING"
ROOM"P1V26_BMC_STBY_VR"
VOLTAGE"0.0V"
BOM_COST"P1V26_BMC_STBY_VR"
SIZE"1B"
CDS_LIB"mstr_symbols";
"A\NAC"7;
%"P3V3_STBY"
"1","(5750,4625)","0","mstr_symbols","I67";
;
CDS_LIB"mstr_symbols"
SIZE"1B"
VOLTAGE"3.3V"
BODY_TYPE"PLUMBING"
HDL_POWER"P3V3_STBY";
"G\NAC"8;
%"GND"
"1","(7475,3850)","0","mstr_symbols","I69";
;
P1V5_STBY_IBMC""
P1V5_STBY_IBMC_VR""
HDL_POWER"GND"
BODY_TYPE"PLUMBING"
ROOM"P1V26_BMC_STBY_VR"
VOLTAGE"0.0V"
SIZE"1B"
BOM_COST"P1V26_BMC_STBY_VR"
CDS_LIB"mstr_symbols";
"A\NAC"9;
%"CAP"
"1","(11725,3575)","0","mstr_discrete","I7";
;
CDS_SEC"1"
PACK_TYPE"0805LF"
PART_NUMBER"C95333-002"
VALUE"22UF"
LOCATION"C9F13"
TOLERANCE"20%"
VOLTAGE"4V"
MATERIAL"X6S"
CDS_LOCATION"C9F13"
CDS_LIB"mstr_discrete"
SEC"1"
SEC_TYPE"0805LF"
ROOM"P1V538_BMC_STBY_VR"
BOM_COST"P1V538_BMC_STBY_VR";
"A"
$PN"1"21;
"B"
$PN"2"17;
%"RT9059"
"1","(8850,3775)","0","mstr_vreg","I70";
;
CDS_SEC"1"
MATERIAL"IC"
LOCATION"EU9F2"
PART_NUMBER"H65765-001"
PACK_TYPE"DFN"
SEC"1"
SEC_TYPE"DFN"
CDS_LOCATION"EU9F2"
CDS_LIB"mstr_vreg";
"VIN<0>"
$PN"7"8;
"VIN<1>"
$PN"8"8;
"VIN<2>"
$PN"9"8;
"EN"
$PN"6"26;
"VOUT<0>"
$PN"1"21;
"VOUT<1>"
$PN"2"21;
"VOUT<2>"
$PN"3"21;
"GND"
$PN"11"7;
"ADJ_NC"
$PN"4"22;
"VDD"
$PN"10"8;
"PGOOD"
$PN"5"25;
%"CAP_A"
"1","(7475,4125)","0","dev_discrete","I71";
;
VOLTAGE"16V"
VALUE"0.1UF"
TOLERANCE"10%"
MATERIAL"X7R"
LOCATION"C9F5"
PACK_TYPE"0402V"
PART_NUMBER"A36096-030"
SEC"1"
SEC_TYPE"0402V"
CDS_SEC"1"
CDS_LIB"dev_discrete"
CDS_LOCATION"C9F5";
"B"
$PN"2"9;
"A"
$PN"1"8;
%"RES"
"1","(10700,4275)","0","mstr_discrete","I72";
;
CDS_SEC"1"
LOCATION"R1T9"
PART_NUMBER"G21796-250"
PACK_TYPE"0402"
VALUE"22.1"
WATTAGE"1/16W"
TOLERANCE"1.0%"
MATERIAL"CHIP"
ROOM"P1V538_BMC_STBY_VR"
SEC"1"
SEC_TYPE"0402"
CDS_LOCATION"R1T9"
CDS_LIB"mstr_discrete";
"B"
$PN"2"29;
"A"
$PN"1"25;
%"RT9059"
"1","(8425,1700)","0","mstr_vreg","I73";
;
CDS_SEC"1"
$SEC"1"
CDS_LOCATION"EU25F2"
LOCATION"EU25F2"
PART_NUMBER"H65765-001"
MATERIAL"IC"
CDS_LIB"mstr_vreg"
PACK_TYPE"DFN";
"VIN<0>"
$PN"7"11;
"VIN<1>"
$PN"8"11;
"VIN<2>"
$PN"9"11;
"EN"
$PN"6"23;
"VOUT<0>"
$PN"1"20;
"VOUT<1>"
$PN"2"20;
"VOUT<2>"
$PN"3"20;
"GND"
$PN"11"16;
"ADJ_NC"
$PN"4"28;
"VDD"
$PN"10"11;
"PGOOD"
$PN"5"27;
%"GND"
"1","(7250,1800)","0","mstr_symbols","I74";
;
P1V5_STBY_IBMC""
P1V5_STBY_IBMC_VR""
ROOM"P1V26_BMC_STBY_VR"
VOLTAGE"0.0V"
SIZE"1B"
BOM_COST"P1V26_BMC_STBY_VR"
CDS_LIB"mstr_symbols"
BODY_TYPE"PLUMBING"
HDL_POWER"GND";
"A\NAC"10;
%"P3V3_STBY"
"1","(5575,2550)","0","mstr_symbols","I75";
;
VOLTAGE"3.3V"
SIZE"1B"
CDS_LIB"mstr_symbols"
BODY_TYPE"PLUMBING"
HDL_POWER"P3V3_STBY";
"G\NAC"11;
%"RES"
"1","(10275,2200)","0","mstr_discrete","I77";
;
CDS_SEC"1"
CDS_LOCATION"R1W9"
PART_NUMBER"G21796-250"
PACK_TYPE"0402"
WATTAGE"1/16W"
VALUE"22.1"
MATERIAL"CHIP"
TOLERANCE"1.0%"
LOCATION"R1W9"
CDS_LIB"mstr_discrete"
ROOM"P1V538_BMC_STBY_VR"
SEC"1"
SEC_TYPE"0402";
"B"
$PN"2"24;
"A"
$PN"1"27;
%"P3V3_STBY"
"1","(9200,2700)","0","mstr_symbols","I78";
;
HDL_POWER"P3V3_STBY"
BODY_TYPE"PLUMBING"
CDS_LIB"mstr_symbols"
VOLTAGE"3.3V"
SIZE"1B";
"G\NAC"12;
%"RES"
"2","(9200,2450)","0","mstr_discrete","I79";
;
CDS_SEC"1"
CDS_LOCATION"R9W12"
PACK_TYPE"0402"
PART_NUMBER"G21796-016"
VALUE"10.0K"
P1V5_STBY_IBMC""
P1V5_STBY_IBMC_VR""
LOCATION"R9W12"
TOLERANCE"1%"
MATERIAL"CHIP"
WATTAGE"1/16W"
CDS_LIB"mstr_discrete"
BOM_COST"P1V538_BMC_STBY_VR"
ROOM"P1V538_BMC_STBY_VR"
SEC"1"
SEC_TYPE"0402";
"A"
$PN"1"12;
"B"
$PN"2"27;
%"CAP"
"1","(11300,1500)","0","mstr_discrete","I81";
;
CDS_SEC"1"
CDS_LOCATION"C9W13"
PART_NUMBER"C95333-002"
MATERIAL"X6S"
TOLERANCE"20%"
PACK_TYPE"0805LF"
LOCATION"C9W13"
VALUE"22UF"
VOLTAGE"4V"
SEC"1"
SEC_TYPE"0805LF"
CDS_LIB"mstr_discrete"
ROOM"P1V538_BMC_STBY_VR"
BOM_COST"P1V538_BMC_STBY_VR";
"A"
$PN"1"20;
"B"
$PN"2"13;
%"GND"
"1","(11300,1175)","0","mstr_symbols","I82";
;
P1V5_STBY_IBMC""
P1V5_STBY_IBMC_VR""
HDL_POWER"GND"
BODY_TYPE"PLUMBING"
CDS_LIB"mstr_symbols"
BOM_COST"P1V538_BMC_STBY_VR"
SIZE"1B"
VOLTAGE"0.0V"
ROOM"P1V538_BMC_STBY_VR";
"A\NAC"13;
%"CAP"
"1","(10450,1500)","0","mstr_discrete","I83";
;
CDS_SEC"1"
CDS_LOCATION"C1W15"
PART_NUMBER"E15431-002"
PACK_TYPE"0603"
TOLERANCE"20%"
VOLTAGE"6.3V"
LOCATION"C1W15"
VALUE"10UF"
MATERIAL"X6S"
BOM_COST"P1V538_BMC_STBY_VR"
ROOM"P1V538_BMC_STBY_VR"
CDS_LIB"mstr_discrete"
SEC_TYPE"0603"
SEC"1";
"A"
$PN"1"20;
"B"
$PN"2"13;
%"CAP"
"1","(9950,2075)","0","mstr_discrete","I84";
;
CDS_SEC"1"
CDS_LOCATION"C9W10"
VOLTAGE"50V"
PART_NUMBER"A36096-046"
TOLERANCE"10%"
VALUE"1000PF"
PACK_TYPE"0402LF"
MATERIAL"X7R"
LOCATION"C9W10"
CDS_LIB"mstr_discrete"
BOM_COST"P1V538_BMC_STBY_VR"
ROOM"P1V538_BMC_STBY_VR"
SEC"1"
SEC_TYPE"0402LF";
"A"
$PN"1"27;
"B"
$PN"2"14;
%"GND"
"1","(9950,1900)","0","mstr_symbols","I85";
;
HDL_POWER"GND"
BODY_TYPE"PLUMBING"
CDS_LIB"mstr_symbols"
BOM_COST"P1V538_BMC_STBY_VR"
SIZE"1B"
VOLTAGE"0.0V"
ROOM"P1V538_BMC_STBY_VR";
"A\NAC"14;
%"GND"
"1","(9925,625)","0","mstr_symbols","I88";
;
P1V5_STBY_IBMC_VR""
P1V5_STBY_IBMC""
HDL_POWER"GND"
BODY_TYPE"PLUMBING"
CDS_LIB"mstr_symbols"
ROOM"P1V538_BMC_STBY_VR"
VOLTAGE"0.0V"
SIZE"1B"
BOM_COST"P1V538_BMC_STBY_VR";
"A\NAC"15;
%"GND"
"1","(9025,1275)","0","mstr_symbols","I89";
;
P1V5_STBY_IBMC_VR""
P1V5_STBY_IBMC""
HDL_POWER"GND"
BODY_TYPE"PLUMBING"
CDS_LIB"mstr_symbols"
SIZE"1B"
BOM_COST"P1V26_BMC_STBY_VR"
VOLTAGE"0.0V"
ROOM"P1V26_BMC_STBY_VR";
"A\NAC"16;
%"GND"
"1","(11725,3225)","0","mstr_symbols","I9";
;
P1V5_STBY_IBMC""
P1V5_STBY_IBMC_VR""
CDS_LIB"mstr_symbols"
BOM_COST"P1V538_BMC_STBY_VR"
SIZE"1B"
VOLTAGE"0.0V"
ROOM"P1V538_BMC_STBY_VR"
BODY_TYPE"PLUMBING"
HDL_POWER"GND";
"A\NAC"17;
%"CAP_A"
"1","(7250,2075)","0","dev_discrete","I90";
;
CDS_SEC"1"
CDS_LOCATION"C9W5"
PART_NUMBER"A36096-030"
PACK_TYPE"0402V"
MATERIAL"X7R"
TOLERANCE"10%"
VALUE"0.1UF"
LOCATION"C9W5"
VOLTAGE"16V"
SEC_TYPE"0402V"
SEC"1"
CDS_LIB"dev_discrete";
"B"
$PN"2"10;
"A"
$PN"1"11;
%"CAP"
"1","(6625,1225)","2","mstr_discrete","I91";
;
CDS_SEC"1"
CDS_LOCATION"C9W6"
VALUE"1000PF"
PART_NUMBER"A36096-046"
LOCATION"C9W6"
VOLTAGE"50V"
TOLERANCE"10%"
MATERIAL"EMPTY"
PACK_TYPE"0402LF"
CDS_LIB"mstr_discrete"
ROOM"P1V538_BMC_STBY_VR"
BOM_COST"P1V538_BMC_STBY_VR"
SEC"1"
SEC_TYPE"0402LF";
"A"
$PN"1"23;
"B"
$PN"2"19;
%"CAP"
"1","(5575,2075)","0","mstr_discrete","I92";
;
CDS_SEC"1"
CDS_LOCATION"C1W7"
PACK_TYPE"0603"
TOLERANCE"20%"
MATERIAL"X6S"
PART_NUMBER"E15431-002"
LOCATION"C1W7"
VALUE"10UF"
VOLTAGE"6.3V"
SEC_TYPE"0603"
SEC"1"
BOM_COST"P1V538_BMC_STBY_VR"
ROOM"P1V538_BMC_STBY_VR"
CDS_LIB"mstr_discrete";
"A"
$PN"1"11;
"B"
$PN"2"18;
%"GND"
"1","(5575,1775)","0","mstr_symbols","I93";
;
VOLTAGE"0.0V"
SIZE"1B"
CDS_LIB"mstr_symbols"
BODY_TYPE"PLUMBING"
HDL_POWER"GND";
"A\NAC"18;
%"GND"
"1","(6625,800)","0","mstr_symbols","I95";
;
P1V5_STBY_IBMC""
P1V5_STBY_IBMC_VR""
HDL_POWER"GND"
BODY_TYPE"PLUMBING"
CDS_LIB"mstr_symbols"
BOM_COST"P1V538_BMC_STBY_VR"
VOLTAGE"0.0V"
SIZE"1B"
ROOM"P1V538_BMC_STBY_VR";
"A\NAC"19;
%"W_VCC_CIRCLE"
"1","(11300,1900)","0","w_power","I96";
;
HDL_POWER"P2V5_AUX_BMC"
BODY_TYPE"PLUMBING"
CDS_LMAN_SYM_OUTLINE"-100,100,100,-100"
CDS_LIB"w_power";
"VCC_CIRCLE \B"20;
%"W_VCC_CIRCLE"
"1","(11725,3975)","0","w_power","I97";
;
HDL_POWER"P1V2_AUX_BMC"
BODY_TYPE"PLUMBING"
CDS_LIB"w_power"
CDS_LMAN_SYM_OUTLINE"-100,100,100,-100";
"VCC_CIRCLE \B"21;
%"5K1R2F-2-GP"
"1","(10350,3525)","0","w_hdl","I98";
;
CDS_SEC"1"
$SEC"1"
CDS_LOCATION"R9F31"
LOCATION"R9F31"
VALUE"5K1R2F-2-GP"
TOLERANCE"1%"
PACK_SIZE"0402"
RATED"1/16W"
ATTRIBUTE"5.1KOHM"
PACK_TYPE"SMD-RG"
PART_NUMBER"64.51015.6DL"
CDS_LIB"w_hdl"
CDS_LMAN_SYM_OUTLINE"-50,75,50,-75";
"2"
$PN"2"22;
"1"
$PN"1"21;
END.
